# BASEBOARD_FAB2 (Tioga Pass) — schematic netlist excerpt (pin names and nets, part order shuffled) for the footprints in the layout excerpt that follows; sources: Cadence DE-HDL packaged netlist, KiCad conversion of Wiwynn_Tioga_Pass_MB.brd

R7E15  RES  22.1 1.0% CHIP  pkg 0402  page 241 : A = PWRGD_P5V_STBY_R ; B = PWRGD_P5V_STBY

T1D9  TEST-PAD-12P-1-GP-U  pkg DISCRET-GB1  page 257
  DP  = L12_85OHM_5INCH_DP
  DN  = L12_85OHM_5INCH_DN
  GND(0)  = GND
  GND(1)  = GND
  GND(2)  = GND
  GND(3)  = GND
  GND(4)  = GND
  GND(5)  = GND
  GND(6)  = GND
  GND(7)  = GND
  GND(8)  = GND
  GND(9)  = GND

(kicad_pcb
	(version 20260206)
	(generator "pcbnew")
	(generator_version "10.0")
	(general
		(thickness 1.6)
		(legacy_teardrops no)
	)
	(paper "A4")
	(title_block
		(title "Wiwynn_Tioga_Pass_MB.brd")
		(comment 1 "Tioga Pass / footprints 1995-1996 of 4770")
	)
	(layers
		(0 "F.Cu" signal "TOP")
		(4 "In1.Cu" signal "L2GND")
		(6 "In2.Cu" signal "L3")
		(8 "In3.Cu" signal "L4GND")
		(10 "In4.Cu" signal "L5")
		(12 "In5.Cu" signal "L6GND")
		(14 "In6.Cu" signal "L7VCC")
		(16 "In7.Cu" signal "L8VCC")
		(18 "In8.Cu" signal "L9GND")
		(20 "In9.Cu" signal "L10")
		(22 "In10.Cu" signal "L11GND")
		(24 "In11.Cu" signal "L12")
		(26 "In12.Cu" signal "L13GND")
		(2 "B.Cu" signal "BOTTOM")
		(9 "F.Adhes" user "F.Adhesive")
		(11 "B.Adhes" user "B.Adhesive")
		(13 "F.Paste" user "Package Geometry/Pastemask Top")
		(15 "B.Paste" user "Package Geometry/Pastemask Bottom")
		(5 "F.SilkS" user "Ref Des/Silkscreen Top")
		(7 "B.SilkS" user "Ref Des/Silkscreen Bottom")
		(1 "F.Mask" user "Board Geometry/Soldermask Top")
		(3 "B.Mask" user "Board Geometry/Soldermask Bottom")
		(17 "Dwgs.User" user "User.Drawings")
		(19 "Cmts.User" user "User.Comments")
		(21 "Eco1.User" user "User.Eco1")
		(23 "Eco2.User" user "User.Eco2")
		(25 "Edge.Cuts" user "Board Geometry/Outline")
		(27 "Margin" user)
		(31 "F.CrtYd" user "Package Geometry/Place Bound Top")
		(29 "B.CrtYd" user "Package Geometry/Place Bound Bottom")
		(35 "F.Fab" user "Ref Des/Assembly Top")
		(33 "B.Fab" user "Ref Des/Assembly Bottom")
	)
	(footprint ""
		(layer "F.Cu")
		(at 101.448616 -164.9857 90)
		(property "Reference" "T1D9"
			(at 0 0 90)
			(layer "F.SilkS")
			(hide yes)
			(effects
				(font
					(size 1.27 1.27)
				)
			)
		)
		(property "Value" "*"
			(at -3.4036 -4.46405 90)
			(unlocked yes)
			(layer "F.Fab")
			(hide yes)
			(effects
				(font
					(size 0.889 0.889)
					(thickness 0.1524)
				)
			)
		)
		(property "Device Type" "TEST-PAD-12P-1-GP-U_DISCRET-GBA"
			(at -3.4036 -5.98805 90)
			(unlocked yes)
			(layer "F.Fab")
			(hide yes)
			(effects
				(font
					(size 0.889 0.889)
					(thickness 0.1524)
				)
			)
		)
		(duplicate_pad_numbers_are_jumpers no)
		(fp_line
			(start 2.3622 -4.826)
			(end 2.3622 3.4798)
			(stroke
				(width 0.1524)
				(type default)
			)
			(layer "F.SilkS")
		)
		(fp_line
			(start -2.3876 -4.826)
			(end 2.3622 -4.826)
			(stroke
				(width 0.1524)
				(type default)
			)
			(layer "F.SilkS")
		)
		(fp_line
			(start 2.3622 3.4798)
			(end -2.3876 3.4798)
			(stroke
				(width 0.1524)
				(type default)
			)
			(layer "F.SilkS")
		)
		(fp_line
			(start -2.3876 3.4798)
			(end -2.3876 -4.826)
			(stroke
				(width 0.1524)
				(type default)
			)
			(layer "F.SilkS")
		)
		(fp_rect
			(start -2.6416 3.7338)
			(end 2.6162 -5.08)
			(stroke
				(width 0)
				(type default)
			)
			(fill no)
			(layer "F.CrtYd")
		)
		(fp_rect
			(start -2.6416 3.7338)
			(end 2.6162 -5.08)
			(stroke
				(width 0)
				(type default)
			)
			(fill no)
			(layer "F.Fab")
		)
		(pad "1" smd circle
			(at 0.496824 -1.301496 90)
			(size 0.6604 0.6604)
			(layers "F.Cu" "F.Mask" "F.Paste")
			(net "L12_85OHM_5INCH_DP")
		)
		(pad "2" smd circle
			(at -0.503936 -1.301496 90)
			(size 0.6604 0.6604)
			(layers "F.Cu" "F.Mask" "F.Paste")
			(net "L12_85OHM_5INCH_DN")
		)
		(pad "3" smd custom
			(at -0.00889 0.370078 90)
			(size 0.74295 0.74295)
			(layers "F.Cu" "F.Mask" "F.Paste")
			(net "GND")
			(options
				(clearance outline)
				(anchor circle)
			)
			(primitives
				(gr_poly
					(pts
						(xy -2.1209 1.4859) (xy 2.1209 1.4859) (xy 2.1209 -1.4859) (xy 1.08585 -1.4859) (xy 1.08585 -0.4699)
						(xy -1.08585 -0.4699) (xy -1.08585 -1.4859) (xy -2.1209 -1.4859)
					)
					(width 0)
					(fill yes)
				)
			)
		)
		(pad "4" thru_hole circle
			(at 1.266444 -3.851656 90)
			(size 1.4478 1.4478)
			(drill 1.0414)
			(layers "*.Cu" "*.Mask")
			(remove_unused_layers no)
			(net "GND")
			(clearance 0.1524)
			(thermal_gap 0.1524)
		)
		(pad "5" thru_hole circle
			(at -1.273556 -3.851656 90)
			(size 1.4478 1.4478)
			(drill 1.0414)
			(layers "*.Cu" "*.Mask")
			(remove_unused_layers no)
			(net "GND")
			(clearance 0.1524)
			(thermal_gap 0.1524)
		)
		(pad "6" thru_hole circle
			(at 1.266444 2.498344 90)
			(size 1.4478 1.4478)
			(drill 1.0414)
			(layers "*.Cu" "*.Mask")
			(remove_unused_layers no)
			(net "GND")
			(clearance 0.1524)
			(thermal_gap 0.1524)
		)
		(pad "7" thru_hole circle
			(at -1.273556 2.498344 90)
			(size 1.4478 1.4478)
			(drill 1.0414)
			(layers "*.Cu" "*.Mask")
			(remove_unused_layers no)
			(net "GND")
			(clearance 0.1524)
			(thermal_gap 0.1524)
		)
		(pad "8" thru_hole circle
			(at 1.27 -0.4572 90)
			(size 0.7112 0.7112)
			(drill 0.4064)
			(layers "*.Cu" "*.Mask")
			(remove_unused_layers no)
			(net "GND")
			(clearance 0.1016)
			(thermal_gap 0.1016)
		)
		(pad "9" thru_hole circle
			(at 1.27 0.762 90)
			(size 0.7112 0.7112)
			(drill 0.4064)
			(layers "*.Cu" "*.Mask")
			(remove_unused_layers no)
			(net "GND")
			(clearance 0.1016)
			(thermal_gap 0.1016)
		)
		(pad "10" thru_hole circle
			(at -0.0254 0.762 90)
			(size 0.7112 0.7112)
			(drill 0.4064)
			(layers "*.Cu" "*.Mask")
			(remove_unused_layers no)
			(net "GND")
			(clearance 0.1016)
			(thermal_gap 0.1016)
		)
		(pad "11" thru_hole circle
			(at -1.27 0.762 90)
			(size 0.7112 0.7112)
			(drill 0.4064)
			(layers "*.Cu" "*.Mask")
			(remove_unused_layers no)
			(net "GND")
			(clearance 0.1016)
			(thermal_gap 0.1016)
		)
		(pad "12" thru_hole circle
			(at -1.27 -0.4572 90)
			(size 0.7112 0.7112)
			(drill 0.4064)
			(layers "*.Cu" "*.Mask")
			(remove_unused_layers no)
			(net "GND")
			(clearance 0.1016)
			(thermal_gap 0.1016)
		)
	)
	(footprint ""
		(layer "F.Cu")
		(at 393.192 -71.0565 180)
		(property "Reference" "R7E15"
			(at 0 0 180)
			(layer "F.SilkS")
			(hide yes)
			(effects
				(font
					(size 1.27 1.27)
				)
			)
		)
		(property "Value" ""
			(at 0 0 180)
			(layer "F.Fab")
			(effects
				(font
					(size 1.27 1.27)
				)
			)
		)
		(duplicate_pad_numbers_are_jumpers no)
		(fp_poly
			(pts
				(xy -0.2794 -0.1016) (xy 0.2794 -0.1016) (xy 0.2794 0.9906) (xy -0.2794 0.9906)
			)
			(stroke
				(width 0)
				(type default)
			)
			(fill no)
			(layer "F.CrtYd")
		)
		(fp_line
			(start 0.2794 0.9906)
			(end 0.2794 -0.1016)
			(stroke
				(width 0.1)
				(type default)
			)
			(layer "F.Fab")
		)
		(fp_line
			(start 0.2794 -0.1016)
			(end -0.2794 -0.1016)
			(stroke
				(width 0.1)
				(type default)
			)
			(layer "F.Fab")
		)
		(fp_line
			(start -0.2794 0.9906)
			(end 0.2794 0.9906)
			(stroke
				(width 0.1)
				(type default)
			)
			(layer "F.Fab")
		)
		(fp_line
			(start -0.2794 -0.1016)
			(end -0.2794 0.9906)
			(stroke
				(width 0.1)
				(type default)
			)
			(layer "F.Fab")
		)
		(pad "1" smd rect
			(at 0 0 180)
			(size 0.508 0.508)
			(layers "F.Cu" "F.Mask" "F.Paste")
			(net "PWRGD_P5V_STBY_R")
		)
		(pad "2" smd rect
			(at 0 0.889 180)
			(size 0.508 0.508)
			(layers "F.Cu" "F.Mask" "F.Paste")
			(net "PWRGD_P5V_STBY")
		)
		(zone
			(layer "F.Cu")
			(hatch none 0.5)
			(connect_pads
				(clearance 0)
			)
			(min_thickness 0.25)
			(keepout
				(tracks not_allowed)
				(vias allowed)
				(pads allowed)
				(copperpour not_allowed)
				(footprints allowed)
			)
			(placement
				(enabled no)
				(sheetname "")
			)
			(fill
				(thermal_gap 0.5)
				(thermal_bridge_width 0.5)
				(island_removal_mode 0)
			)
			(polygon
				(pts
					(xy 393.446 -71.6915) (xy 392.938 -71.6915) (xy 392.938 -71.3105) (xy 393.446 -71.3105)
				)
			)
		)
		(zone
			(layer "F.Cu")
			(hatch none 0.5)
			(connect_pads
				(clearance 0)
			)
			(min_thickness 0.25)
			(keepout
				(tracks allowed)
				(vias not_allowed)
				(pads allowed)
				(copperpour not_allowed)
				(footprints allowed)
			)
			(placement
				(enabled no)
				(sheetname "")
			)
			(fill
				(thermal_gap 0.5)
				(thermal_bridge_width 0.5)
				(island_removal_mode 0)
			)
			(polygon
				(pts
					(xy 393.446 -71.3105) (xy 392.938 -71.3105) (xy 392.938 -71.6915) (xy 393.446 -71.6915)
				)
			)
		)
	)
)
